(kicad_pcb
	(version 20260206)
	(generator "pcbnew")
	(generator_version "10.0")
	(general
		(thickness 1.6)
		(legacy_teardrops no)
	)
	(paper "A4")
	(title_block
		(title "dpb — 14545-sa.0730WZS0815.brd")
		(comment 1 "Honey Badger (Wiwynn) / footprints 1059-1065 of 1066")
	)
	(layers
		(0 "F.Cu" signal "TOP")
		(4 "In1.Cu" signal "L2GND")
		(6 "In2.Cu" signal "L3")
		(8 "In3.Cu" signal "L4VCC")
		(10 "In4.Cu" signal "L5VCC")
		(12 "In5.Cu" signal "L6")
		(14 "In6.Cu" signal "L7GND")
		(2 "B.Cu" signal "BOTTOM")
		(9 "F.Adhes" user "F.Adhesive")
		(11 "B.Adhes" user "B.Adhesive")
		(13 "F.Paste" user "Package Geometry/Pastemask Top")
		(15 "B.Paste" user "Package Geometry/Pastemask Bottom")
		(5 "F.SilkS" user "Ref Des/Silkscreen Top")
		(7 "B.SilkS" user "Ref Des/Silkscreen Bottom")
		(1 "F.Mask" user "Board Geometry/Soldermask Top")
		(3 "B.Mask" user "Board Geometry/Soldermask Bottom")
		(17 "Dwgs.User" user "User.Drawings")
		(19 "Cmts.User" user "User.Comments")
		(21 "Eco1.User" user "User.Eco1")
		(23 "Eco2.User" user "User.Eco2")
		(25 "Edge.Cuts" user "Board Geometry/Outline")
		(27 "Margin" user)
		(31 "F.CrtYd" user "Package Geometry/Place Bound Top")
		(29 "B.CrtYd" user "Package Geometry/Place Bound Bottom")
		(35 "F.Fab" user "Ref Des/Assembly Top")
		(33 "B.Fab" user "Ref Des/Assembly Bottom")
	)
	(footprint ""
		(layer "F.Cu")
		(at 230.364284 -142.972028 90)
		(property "Reference" "R146"
			(at 0 0 90)
			(layer "F.SilkS")
			(hide yes)
			(effects
				(font
					(size 1.27 1.27)
				)
			)
		)
		(property "Value" "0R2J-2-GP"
			(at 0.064008 -3.993896 90)
			(unlocked yes)
			(layer "F.Fab")
			(hide yes)
			(effects
				(font
					(size 1.016 1.016)
					(thickness 0.1524)
				)
			)
		)
		(property "Device Type" "R402H16"
			(at 0.064008 -5.517896 90)
			(unlocked yes)
			(layer "F.Fab")
			(hide yes)
			(effects
				(font
					(size 1.016 1.016)
					(thickness 0.1524)
				)
			)
		)
		(duplicate_pad_numbers_are_jumpers no)
		(fp_line
			(start 0.508 -0.9398)
			(end -0.508 -0.9398)
			(stroke
				(width 0.1524)
				(type default)
			)
			(layer "F.SilkS")
		)
		(fp_line
			(start -0.508 -0.9398)
			(end -0.508 0.9398)
			(stroke
				(width 0.1524)
				(type default)
			)
			(layer "F.SilkS")
		)
		(fp_rect
			(start -0.508 0.9398)
			(end 0.508 -0.9398)
			(stroke
				(width 0)
				(type default)
			)
			(fill no)
			(layer "F.CrtYd")
		)
		(fp_rect
			(start -0.508 0.9398)
			(end 0.508 -0.9398)
			(stroke
				(width 0)
				(type default)
			)
			(fill no)
			(layer "F.Fab")
		)
		(pad "1" smd custom
			(at 0 -0.4445 90)
			(size 0.1397 0.1397)
			(layers "F.Cu" "F.Mask" "F.Paste")
			(net "FLT_NET_HDD3")
			(options
				(clearance outline)
				(anchor circle)
			)
			(primitives
				(gr_poly
					(pts
						(arc
							(start -0.1778 -0.2794)
							(mid -0.249642 -0.249642)
							(end -0.2794 -0.1778)
						)
						(arc
							(start -0.2794 0.1778)
							(mid -0.249642 0.249642)
							(end -0.1778 0.2794)
						)
						(arc
							(start 0.1778 0.2794)
							(mid 0.249642 0.249642)
							(end 0.2794 0.1778)
						)
						(arc
							(start 0.2794 -0.1778)
							(mid 0.249642 -0.249642)
							(end 0.1778 -0.2794)
						)
					)
					(width 0)
					(fill yes)
				)
			)
		)
		(pad "2" smd custom
			(at 0 0.4445 90)
			(size 0.1397 0.1397)
			(layers "F.Cu" "F.Mask" "F.Paste")
			(net "FLT_HDD3_DRIVE")
			(options
				(clearance outline)
				(anchor circle)
			)
			(primitives
				(gr_poly
					(pts
						(arc
							(start -0.1778 -0.2794)
							(mid -0.249642 -0.249642)
							(end -0.2794 -0.1778)
						)
						(arc
							(start -0.2794 0.1778)
							(mid -0.249642 0.249642)
							(end -0.1778 0.2794)
						)
						(arc
							(start 0.1778 0.2794)
							(mid 0.249642 0.249642)
							(end 0.2794 0.1778)
						)
						(arc
							(start 0.2794 -0.1778)
							(mid 0.249642 -0.249642)
							(end 0.1778 -0.2794)
						)
					)
					(width 0)
					(fill yes)
				)
			)
		)
	)
	(footprint ""
		(layer "F.Cu")
		(at 202.564746 -186.9567 -90)
		(property "Reference" "R434"
			(at 0 0 270)
			(layer "F.SilkS")
			(hide yes)
			(effects
				(font
					(size 1.27 1.27)
				)
			)
		)
		(property "Value" "4K7R2J-2-GP"
			(at 0.064008 -3.993896 270)
			(unlocked yes)
			(layer "F.Fab")
			(hide yes)
			(effects
				(font
					(size 1.016 1.016)
					(thickness 0.1524)
				)
			)
		)
		(property "Device Type" "R402H16"
			(at 0.064008 -5.517896 270)
			(unlocked yes)
			(layer "F.Fab")
			(hide yes)
			(effects
				(font
					(size 1.016 1.016)
					(thickness 0.1524)
				)
			)
		)
		(duplicate_pad_numbers_are_jumpers no)
		(fp_line
			(start -0.508 -0.9398)
			(end -0.508 0.9398)
			(stroke
				(width 0.1524)
				(type default)
			)
			(layer "F.SilkS")
		)
		(fp_line
			(start 0.508 -0.9398)
			(end -0.508 -0.9398)
			(stroke
				(width 0.1524)
				(type default)
			)
			(layer "F.SilkS")
		)
		(fp_rect
			(start -0.508 0.9398)
			(end 0.508 -0.9398)
			(stroke
				(width 0)
				(type default)
			)
			(fill no)
			(layer "F.CrtYd")
		)
		(fp_rect
			(start -0.508 0.9398)
			(end 0.508 -0.9398)
			(stroke
				(width 0)
				(type default)
			)
			(fill no)
			(layer "F.Fab")
		)
		(pad "1" smd custom
			(at 0 -0.4445 270)
			(size 0.1397 0.1397)
			(layers "F.Cu" "F.Mask" "F.Paste")
			(net "P3V3")
			(options
				(clearance outline)
				(anchor circle)
			)
			(primitives
				(gr_poly
					(pts
						(arc
							(start -0.1778 -0.2794)
							(mid -0.249642 -0.249642)
							(end -0.2794 -0.1778)
						)
						(arc
							(start -0.2794 0.1778)
							(mid -0.249642 0.249642)
							(end -0.1778 0.2794)
						)
						(arc
							(start 0.1778 0.2794)
							(mid 0.249642 0.249642)
							(end 0.2794 0.1778)
						)
						(arc
							(start 0.2794 -0.1778)
							(mid 0.249642 -0.249642)
							(end 0.1778 -0.2794)
						)
					)
					(width 0)
					(fill yes)
				)
			)
		)
		(pad "2" smd custom
			(at 0 0.4445 270)
			(size 0.1397 0.1397)
			(layers "F.Cu" "F.Mask" "F.Paste")
			(net "SAS2X28_A_HDD3_FLT")
			(options
				(clearance outline)
				(anchor circle)
			)
			(primitives
				(gr_poly
					(pts
						(arc
							(start -0.1778 -0.2794)
							(mid -0.249642 -0.249642)
							(end -0.2794 -0.1778)
						)
						(arc
							(start -0.2794 0.1778)
							(mid -0.249642 0.249642)
							(end -0.1778 0.2794)
						)
						(arc
							(start 0.1778 0.2794)
							(mid 0.249642 0.249642)
							(end 0.2794 0.1778)
						)
						(arc
							(start 0.2794 -0.1778)
							(mid 0.249642 -0.249642)
							(end 0.1778 -0.2794)
						)
					)
					(width 0)
					(fill yes)
				)
			)
		)
	)
	(footprint ""
		(layer "F.Cu")
		(at 176.669446 -463.711036 90)
		(property "Reference" "R382"
			(at 0 0 90)
			(layer "F.SilkS")
			(hide yes)
			(effects
				(font
					(size 1.27 1.27)
				)
			)
		)
		(property "Value" "0R2J-2-GP"
			(at 0.064008 -3.993896 90)
			(unlocked yes)
			(layer "F.Fab")
			(hide yes)
			(effects
				(font
					(size 1.016 1.016)
					(thickness 0.1524)
				)
			)
		)
		(property "Device Type" "R402H16"
			(at 0.064008 -5.517896 90)
			(unlocked yes)
			(layer "F.Fab")
			(hide yes)
			(effects
				(font
					(size 1.016 1.016)
					(thickness 0.1524)
				)
			)
		)
		(duplicate_pad_numbers_are_jumpers no)
		(fp_line
			(start 0.508 -0.9398)
			(end -0.508 -0.9398)
			(stroke
				(width 0.1524)
				(type default)
			)
			(layer "F.SilkS")
		)
		(fp_line
			(start -0.508 -0.9398)
			(end -0.508 0.9398)
			(stroke
				(width 0.1524)
				(type default)
			)
			(layer "F.SilkS")
		)
		(fp_rect
			(start -0.508 0.9398)
			(end 0.508 -0.9398)
			(stroke
				(width 0)
				(type default)
			)
			(fill no)
			(layer "F.CrtYd")
		)
		(fp_rect
			(start -0.508 0.9398)
			(end 0.508 -0.9398)
			(stroke
				(width 0)
				(type default)
			)
			(fill no)
			(layer "F.Fab")
		)
		(pad "1" smd custom
			(at 0 -0.4445 90)
			(size 0.1397 0.1397)
			(layers "F.Cu" "F.Mask" "F.Paste")
			(net "VOL_SEN_SDA")
			(options
				(clearance outline)
				(anchor circle)
			)
			(primitives
				(gr_poly
					(pts
						(arc
							(start -0.1778 -0.2794)
							(mid -0.249642 -0.249642)
							(end -0.2794 -0.1778)
						)
						(arc
							(start -0.2794 0.1778)
							(mid -0.249642 0.249642)
							(end -0.1778 0.2794)
						)
						(arc
							(start 0.1778 0.2794)
							(mid 0.249642 0.249642)
							(end 0.2794 0.1778)
						)
						(arc
							(start 0.2794 -0.1778)
							(mid 0.249642 -0.249642)
							(end 0.1778 -0.2794)
						)
					)
					(width 0)
					(fill yes)
				)
			)
		)
		(pad "2" smd custom
			(at 0 0.4445 90)
			(size 0.1397 0.1397)
			(layers "F.Cu" "F.Mask" "F.Paste")
			(net "I2C_B_SDA")
			(options
				(clearance outline)
				(anchor circle)
			)
			(primitives
				(gr_poly
					(pts
						(arc
							(start -0.1778 -0.2794)
							(mid -0.249642 -0.249642)
							(end -0.2794 -0.1778)
						)
						(arc
							(start -0.2794 0.1778)
							(mid -0.249642 0.249642)
							(end -0.1778 0.2794)
						)
						(arc
							(start 0.1778 0.2794)
							(mid 0.249642 0.249642)
							(end 0.2794 0.1778)
						)
						(arc
							(start 0.2794 -0.1778)
							(mid 0.249642 -0.249642)
							(end 0.1778 -0.2794)
						)
					)
					(width 0)
					(fill yes)
				)
			)
		)
	)
	(footprint ""
		(layer "F.Cu")
		(at 29.845 -417.449)
		(property "Reference" "C274"
			(at 0 0 0)
			(layer "F.SilkS")
			(hide yes)
			(effects
				(font
					(size 1.27 1.27)
				)
			)
		)
		(property "Value" "SC10U25V6KX-1GP"
			(at -0.0762 -5.1308 0)
			(unlocked yes)
			(layer "F.Fab")
			(hide yes)
			(effects
				(font
					(size 1.016 1.016)
					(thickness 0.1524)
				)
			)
		)
		(property "Device Type" "C1206H71"
			(at -0.127 -6.6548 0)
			(unlocked yes)
			(layer "F.Fab")
			(hide yes)
			(effects
				(font
					(size 1.016 1.016)
					(thickness 0.1524)
				)
			)
		)
		(duplicate_pad_numbers_are_jumpers no)
		(fp_line
			(start -1.016 -2.2352)
			(end 1.016 -2.2352)
			(stroke
				(width 0.1524)
				(type default)
			)
			(layer "F.SilkS")
		)
		(fp_line
			(start -1.016 -0.8382)
			(end -1.016 -2.2352)
			(stroke
				(width 0.1524)
				(type default)
			)
			(layer "F.SilkS")
		)
		(fp_line
			(start -1.016 2.2352)
			(end -1.016 0.8382)
			(stroke
				(width 0.1524)
				(type default)
			)
			(layer "F.SilkS")
		)
		(fp_line
			(start 1.016 -2.2352)
			(end 1.016 -0.8382)
			(stroke
				(width 0.1524)
				(type default)
			)
			(layer "F.SilkS")
		)
		(fp_line
			(start 1.016 0.8382)
			(end 1.016 2.2352)
			(stroke
				(width 0.1524)
				(type default)
			)
			(layer "F.SilkS")
		)
		(fp_line
			(start 1.016 2.2352)
			(end -1.016 2.2352)
			(stroke
				(width 0.1524)
				(type default)
			)
			(layer "F.SilkS")
		)
		(fp_rect
			(start -1.0922 2.3114)
			(end 1.0922 -2.3114)
			(stroke
				(width 0)
				(type default)
			)
			(fill no)
			(layer "F.CrtYd")
		)
		(fp_poly
			(pts
				(xy 1.0922 -2.3114) (xy 1.0922 2.3114) (xy -1.0922 2.3114) (xy -1.0922 -2.3114)
			)
			(stroke
				(width 0)
				(type default)
			)
			(fill no)
			(layer "F.Fab")
		)
		(pad "1" smd rect
			(at 0 -1.397)
			(size 1.651 1.27)
			(layers "F.Cu" "F.Mask" "F.Paste")
			(net "P12V_HDD10")
		)
		(pad "2" smd rect
			(at 0 1.397)
			(size 1.651 1.27)
			(layers "F.Cu" "F.Mask" "F.Paste")
			(net "GND")
		)
	)
	(footprint ""
		(layer "F.Cu")
		(at 25.991312 -338.696808 90)
		(property "Reference" "C281"
			(at 0 0 90)
			(layer "F.SilkS")
			(hide yes)
			(effects
				(font
					(size 1.27 1.27)
				)
			)
		)
		(property "Value" "SCD01U50V2KX-1GP"
			(at 1.1811 -2.7051 90)
			(unlocked yes)
			(layer "F.Fab")
			(hide yes)
			(effects
				(font
					(size 1.016 1.016)
					(thickness 0.1524)
				)
			)
		)
		(property "Device Type" "C402H22"
			(at 1.1811 -4.2291 90)
			(unlocked yes)
			(layer "F.Fab")
			(hide yes)
			(effects
				(font
					(size 1.016 1.016)
					(thickness 0.1524)
				)
			)
		)
		(duplicate_pad_numbers_are_jumpers no)
		(fp_rect
			(start -0.4318 0.9525)
			(end 0.4318 -0.9525)
			(stroke
				(width 0)
				(type default)
			)
			(fill no)
			(layer "F.CrtYd")
		)
		(fp_rect
			(start -0.4318 0.9525)
			(end 0.4318 -0.9525)
			(stroke
				(width 0)
				(type default)
			)
			(fill no)
			(layer "F.Fab")
		)
		(pad "1" smd custom
			(at 0 -0.4445 90)
			(size 0.1524 0.1524)
			(layers "F.Cu" "F.Mask" "F.Paste")
			(net "SAS2X28_DRIVE_RX_P_B11")
			(options
				(clearance outline)
				(anchor circle)
			)
			(primitives
				(gr_poly
					(pts
						(arc
							(start 0.3048 -0.2032)
							(mid 0.275042 -0.275042)
							(end 0.2032 -0.3048)
						)
						(arc
							(start -0.2032 -0.3048)
							(mid -0.275042 -0.275042)
							(end -0.3048 -0.2032)
						)
						(arc
							(start -0.3048 0.2032)
							(mid -0.275042 0.275042)
							(end -0.2032 0.3048)
						)
						(arc
							(start 0.2032 0.3048)
							(mid 0.275042 0.275042)
							(end 0.3048 0.2032)
						)
					)
					(width 0)
					(fill yes)
				)
			)
		)
		(pad "2" smd custom
			(at 0 0.4445 90)
			(size 0.1524 0.1524)
			(layers "F.Cu" "F.Mask" "F.Paste")
			(net "SAS2X28_B_HDD11_RX_+")
			(options
				(clearance outline)
				(anchor circle)
			)
			(primitives
				(gr_poly
					(pts
						(arc
							(start 0.3048 -0.2032)
							(mid 0.275042 -0.275042)
							(end 0.2032 -0.3048)
						)
						(arc
							(start -0.2032 -0.3048)
							(mid -0.275042 -0.275042)
							(end -0.3048 -0.2032)
						)
						(arc
							(start -0.3048 0.2032)
							(mid -0.275042 0.275042)
							(end -0.2032 0.3048)
						)
						(arc
							(start 0.2032 0.3048)
							(mid 0.275042 0.275042)
							(end 0.3048 0.2032)
						)
					)
					(width 0)
					(fill yes)
				)
			)
		)
	)
	(footprint ""
		(layer "F.Cu")
		(at 27.177746 -32.9057 90)
		(property "Reference" "C328"
			(at 0 0 90)
			(layer "F.SilkS")
			(hide yes)
			(effects
				(font
					(size 1.27 1.27)
				)
			)
		)
		(property "Value" "SCD01U50V2KX-1GP"
			(at 1.1811 -2.7051 90)
			(unlocked yes)
			(layer "F.Fab")
			(hide yes)
			(effects
				(font
					(size 1.016 1.016)
					(thickness 0.1524)
				)
			)
		)
		(property "Device Type" "C402H22"
			(at 1.1811 -4.2291 90)
			(unlocked yes)
			(layer "F.Fab")
			(hide yes)
			(effects
				(font
					(size 1.016 1.016)
					(thickness 0.1524)
				)
			)
		)
		(duplicate_pad_numbers_are_jumpers no)
		(fp_rect
			(start -0.4318 0.9525)
			(end 0.4318 -0.9525)
			(stroke
				(width 0)
				(type default)
			)
			(fill no)
			(layer "F.CrtYd")
		)
		(fp_rect
			(start -0.4318 0.9525)
			(end 0.4318 -0.9525)
			(stroke
				(width 0)
				(type default)
			)
			(fill no)
			(layer "F.Fab")
		)
		(pad "1" smd custom
			(at 0 -0.4445 90)
			(size 0.1524 0.1524)
			(layers "F.Cu" "F.Mask" "F.Paste")
			(net "SAS2X28_DRIVE_RX_N_B14")
			(options
				(clearance outline)
				(anchor circle)
			)
			(primitives
				(gr_poly
					(pts
						(arc
							(start 0.3048 -0.2032)
							(mid 0.275042 -0.275042)
							(end 0.2032 -0.3048)
						)
						(arc
							(start -0.2032 -0.3048)
							(mid -0.275042 -0.275042)
							(end -0.3048 -0.2032)
						)
						(arc
							(start -0.3048 0.2032)
							(mid -0.275042 0.275042)
							(end -0.2032 0.3048)
						)
						(arc
							(start 0.2032 0.3048)
							(mid 0.275042 0.275042)
							(end 0.3048 0.2032)
						)
					)
					(width 0)
					(fill yes)
				)
			)
		)
		(pad "2" smd custom
			(at 0 0.4445 90)
			(size 0.1524 0.1524)
			(layers "F.Cu" "F.Mask" "F.Paste")
			(net "SAS2X28_B_HDD14_RX_-")
			(options
				(clearance outline)
				(anchor circle)
			)
			(primitives
				(gr_poly
					(pts
						(arc
							(start 0.3048 -0.2032)
							(mid 0.275042 -0.275042)
							(end 0.2032 -0.3048)
						)
						(arc
							(start -0.2032 -0.3048)
							(mid -0.275042 -0.275042)
							(end -0.3048 -0.2032)
						)
						(arc
							(start -0.3048 0.2032)
							(mid -0.275042 0.275042)
							(end -0.2032 0.3048)
						)
						(arc
							(start 0.2032 0.3048)
							(mid 0.275042 0.275042)
							(end 0.3048 0.2032)
						)
					)
					(width 0)
					(fill yes)
				)
			)
		)
	)
	(footprint ""
		(layer "F.Cu")
		(at 202.564746 -287.7947 -90)
		(property "Reference" "R430"
			(at 0 0 270)
			(layer "F.SilkS")
			(hide yes)
			(effects
				(font
					(size 1.27 1.27)
				)
			)
		)
		(property "Value" "4K7R2J-2-GP"
			(at 0.064008 -3.993896 270)
			(unlocked yes)
			(layer "F.Fab")
			(hide yes)
			(effects
				(font
					(size 1.016 1.016)
					(thickness 0.1524)
				)
			)
		)
		(property "Device Type" "R402H16"
			(at 0.064008 -5.517896 270)
			(unlocked yes)
			(layer "F.Fab")
			(hide yes)
			(effects
				(font
					(size 1.016 1.016)
					(thickness 0.1524)
				)
			)
		)
		(duplicate_pad_numbers_are_jumpers no)
		(fp_line
			(start -0.508 -0.9398)
			(end -0.508 0.9398)
			(stroke
				(width 0.1524)
				(type default)
			)
			(layer "F.SilkS")
		)
		(fp_line
			(start 0.508 -0.9398)
			(end -0.508 -0.9398)
			(stroke
				(width 0.1524)
				(type default)
			)
			(layer "F.SilkS")
		)
		(fp_rect
			(start -0.508 0.9398)
			(end 0.508 -0.9398)
			(stroke
				(width 0)
				(type default)
			)
			(fill no)
			(layer "F.CrtYd")
		)
		(fp_rect
			(start -0.508 0.9398)
			(end 0.508 -0.9398)
			(stroke
				(width 0)
				(type default)
			)
			(fill no)
			(layer "F.Fab")
		)
		(pad "1" smd custom
			(at 0 -0.4445 270)
			(size 0.1397 0.1397)
			(layers "F.Cu" "F.Mask" "F.Paste")
			(net "P3V3")
			(options
				(clearance outline)
				(anchor circle)
			)
			(primitives
				(gr_poly
					(pts
						(arc
							(start -0.1778 -0.2794)
							(mid -0.249642 -0.249642)
							(end -0.2794 -0.1778)
						)
						(arc
							(start -0.2794 0.1778)
							(mid -0.249642 0.249642)
							(end -0.1778 0.2794)
						)
						(arc
							(start 0.1778 0.2794)
							(mid 0.249642 0.249642)
							(end 0.2794 0.1778)
						)
						(arc
							(start 0.2794 -0.1778)
							(mid 0.249642 -0.249642)
							(end 0.1778 -0.2794)
						)
					)
					(width 0)
					(fill yes)
				)
			)
		)
		(pad "2" smd custom
			(at 0 0.4445 270)
			(size 0.1397 0.1397)
			(layers "F.Cu" "F.Mask" "F.Paste")
			(net "SAS2X28_B_HDD2_FLT")
			(options
				(clearance outline)
				(anchor circle)
			)
			(primitives
				(gr_poly
					(pts
						(arc
							(start -0.1778 -0.2794)
							(mid -0.249642 -0.249642)
							(end -0.2794 -0.1778)
						)
						(arc
							(start -0.2794 0.1778)
							(mid -0.249642 0.249642)
							(end -0.1778 0.2794)
						)
						(arc
							(start 0.1778 0.2794)
							(mid 0.249642 0.249642)
							(end 0.2794 0.1778)
						)
						(arc
							(start 0.2794 -0.1778)
							(mid 0.249642 -0.249642)
							(end 0.1778 -0.2794)
						)
					)
					(width 0)
					(fill yes)
				)
			)
		)
	)
)
